FILE_TYPE = MACRO_DRAWING;
SET COLOR_WIRE YELLOW;
SET COLOR_PROP ORANGE;
SET COLOR_DOT WHITE;
SET COLOR_ARC YELLOW;
SET COLOR_BODY GREEN;
SET COLOR_NOTE PURPLE;
SET PROP_DISPLAY VALUE;
SET PAGE_NUMBER P296;
FORCEADD UNIVERSAL_POWER..1
(1350 3875);
FORCEPROP 3 LASTPIN (1350 3825) SIG_NAME P3V3_AUX\g
J 0
(1360 3835);
DISPLAY 0.659574 (1360 3835);
PAINT MONO (1360 3835);
DISPLAY INVISIBLE (1360 3835);
FORCEPROP 1 LAST HDL_POWER P3V3_AUX
J 1
(1350 3925);
DISPLAY 0.872340 (1350 3925);
PAINT GREEN (1350 3925);
FORCEPROP 2 LAST CDS_LIB logical_power
J 0
(1350 3875);
PAINT MONO (1350 3875);
DISPLAY INVISIBLE (1350 3875);
FORCEPROP 1 LAST PATH I11
J 0
(1400 3900);
DISPLAY 0.872340 (1400 3900);
PAINT AQUA (1400 3900);
DISPLAY INVISIBLE (1400 3900);
FORCEADD UNIVERSAL_GND..1
(1350 3325);
FORCEPROP 3 LASTPIN (1350 3375) SIG_NAME GND\g
J 0
(1360 3385);
DISPLAY 0.659574 (1360 3385);
PAINT MONO (1360 3385);
DISPLAY INVISIBLE (1360 3385);
FORCEPROP 1 LAST HDL_POWER GND
J 1
(1375 3250);
DISPLAY 0.872340 (1375 3250);
PAINT GREEN (1375 3250);
DISPLAY INVISIBLE (1375 3250);
FORCEPROP 2 LAST CDS_LIB logical_power
J 0
(1350 3325);
PAINT MONO (1350 3325);
DISPLAY INVISIBLE (1350 3325);
FORCEPROP 1 LAST PATH I12
J 0
(1425 3325);
DISPLAY 0.872340 (1425 3325);
PAINT AQUA (1425 3325);
DISPLAY INVISIBLE (1425 3325);
FORCEADD Q_CAP..1
(1350 3550);
FORCEPROP 1 LAST PART_NUMBER CH4104K1B00
J 0
(1400 3400);
DISPLAY 0.510638 (1400 3400);
DISPLAY INVISIBLE (1400 3400);
FORCEPROP 1 LAST TOLERANCE 10%
J 0
(1400 3500);
DISPLAY 0.510638 (1400 3500);
FORCEPROP 1 LAST VOLTAGE 25V
J 0
(1400 3550);
DISPLAY 0.510638 (1400 3550);
FORCEPROP 1 LAST PACK_TYPE 0402
J 0
(1400 3350);
DISPLAY 0.510638 (1400 3350);
FORCEPROP 1 LAST VALUE 0.1UF
J 0
(1400 3600);
DISPLAY 0.510638 (1400 3600);
FORCEPROP 1 LAST MATERIAL X7R
J 0
(1400 3450);
DISPLAY 0.510638 (1400 3450);
FORCEPROP 1 LAST $LOCATION C1963
J 0
(1400 3650);
DISPLAY 0.787234 (1400 3650);
FORCEPROP 1 LASTPIN (1350 3650) $PN 1
J 0
(1360 3630);
DISPLAY 0.787234 (1360 3630);
FORCEPROP 1 LASTPIN (1350 3450) $PN 2
J 0
(1360 3430);
DISPLAY 0.787234 (1360 3430);
FORCEPROP 2 LAST CDS_LIB pure_quanta
J 2
(1350 3550);
PAINT MONO (1350 3550);
DISPLAY INVISIBLE (1350 3550);
FORCEPROP 1 LAST PATH I13
J 0
(1400 3700);
DISPLAY 0.978723 (1400 3700);
PAINT WHITE (1400 3700);
DISPLAY INVISIBLE (1400 3700);
FORCEPROP 2 LAST CDS_LOCATION C1963
J 0
(1400 3750);
DISPLAY 1.021277 (1400 3750);
DISPLAY INVISIBLE (1400 3750);
FORCEPROP 2 LAST $SEC 1
J 0
(1400 3750);
DISPLAY 0.680851 (1400 3750);
PAINT MONO (1400 3750);
DISPLAY INVISIBLE (1400 3750);
FORCEPROP 2 LAST CDS_SEC 1
J 0
(1400 3750);
DISPLAY 1.021277 (1400 3750);
DISPLAY INVISIBLE (1400 3750);
FORCEADD 74LVC2G07DW7..1
(775 3750);
FORCEPROP 1 LAST PART_NUMBER AL002G07003
J 0
(606 3984);
DISPLAY 0.723404 (606 3984);
PAINT GREEN (606 3984);
DISPLAY INVISIBLE (606 3984);
FORCEPROP 2 LAST VALUE 74LVC2G07DW-7
J 0
(475 4050);
DISPLAY 1.021277 (475 4050);
FORCEPROP 2 LAST PART_TYPE SMLF
J 0
(625 4225);
DISPLAY 1.021277 (625 4225);
FORCEPROP 1 LAST MATERIAL IC
J 0
(606 3857);
DISPLAY 0.723404 (606 3857);
PAINT GREEN (606 3857);
FORCEPROP 1 LAST $LOCATION U255
J 0
(606 4131);
DISPLAY 0.723404 (606 4131);
PAINT GREEN (606 4131);
FORCEPROP 0 LASTPIN (450 3800) $PN 1
J 2
(440 3810);
DISPLAY 0.680851 (440 3810);
PAINT MONO (440 3810);
FORCEPROP 0 LASTPIN (1100 3800) $PN 6
J 0
(1110 3810);
DISPLAY 0.680851 (1110 3810);
PAINT MONO (1110 3810);
FORCEPROP 0 LASTPIN (450 3700) $PN 3
J 2
(440 3710);
DISPLAY 0.680851 (440 3710);
PAINT MONO (440 3710);
FORCEPROP 0 LASTPIN (1100 3700) $PN 4
J 0
(1110 3710);
DISPLAY 0.680851 (1110 3710);
PAINT MONO (1110 3710);
FORCEPROP 0 LASTPIN (450 3750) $PN 2
J 2
(440 3760);
DISPLAY 0.680851 (440 3760);
PAINT MONO (440 3760);
FORCEPROP 0 LASTPIN (1100 3750) $PN 5
J 0
(1110 3760);
DISPLAY 0.680851 (1110 3760);
PAINT MONO (1110 3760);
FORCEPROP 1 LAST PATH I16
J 0
(775 3750);
DISPLAY 0.723404 (775 3750);
PAINT GREEN (775 3750);
DISPLAY INVISIBLE (775 3750);
FORCEPROP 2 LAST CDS_LIB pure_quanta
J 0
(775 3750);
DISPLAY INVISIBLE (775 3750);
FORCEPROP 1 LAST NEEDS_NO_SIZE TRUE
J 0
(775 3750);
DISPLAY 0.723404 (775 3750);
PAINT GREEN (775 3750);
DISPLAY INVISIBLE (775 3750);
FORCEPROP 1 LAST CDS_LMAN_SYM_OUTLINE -175,100,175,-100
J 0
(775 3750);
DISPLAY 0.468085 (775 3750);
PAINT GREEN (775 3750);
DISPLAY INVISIBLE (775 3750);
FORCEPROP 0 LAST CDS_LOCATION U255
J 0
(625 4275);
DISPLAY 1.021277 (625 4275);
DISPLAY INVISIBLE (625 4275);
FORCEPROP 0 LAST $SEC 1
J 0
(625 4275);
DISPLAY 0.680851 (625 4275);
PAINT MONO (625 4275);
DISPLAY INVISIBLE (625 4275);
FORCEPROP 0 LAST CDS_SEC 1
J 0
(625 4275);
DISPLAY 1.021277 (625 4275);
DISPLAY INVISIBLE (625 4275);
FORCEADD UNIVERSAL_GND..1
(200 3600);
FORCEPROP 3 LASTPIN (200 3650) SIG_NAME GND\g
J 0
(210 3660);
DISPLAY 0.659574 (210 3660);
PAINT MONO (210 3660);
DISPLAY INVISIBLE (210 3660);
FORCEPROP 1 LAST HDL_POWER GND
J 1
(225 3525);
DISPLAY 0.872340 (225 3525);
PAINT GREEN (225 3525);
DISPLAY INVISIBLE (225 3525);
FORCEPROP 2 LAST CDS_LIB logical_power
J 0
(200 3600);
DISPLAY INVISIBLE (200 3600);
FORCEPROP 1 LAST PATH I17
J 0
(275 3600);
DISPLAY 0.872340 (275 3600);
PAINT AQUA (275 3600);
DISPLAY INVISIBLE (275 3600);
FORCEADD UNIVERSAL_POWER..1
(-650 4825);
FORCEPROP 3 LASTPIN (-650 4775) SIG_NAME P3V3_AUX\g
J 0
(-640 4785);
DISPLAY 0.659574 (-640 4785);
PAINT MONO (-640 4785);
DISPLAY INVISIBLE (-640 4785);
FORCEPROP 1 LAST HDL_POWER P3V3_AUX
J 1
(-650 4875);
DISPLAY 0.872340 (-650 4875);
PAINT GREEN (-650 4875);
FORCEPROP 2 LAST CDS_LIB logical_power
J 0
(-650 4825);
PAINT MONO (-650 4825);
DISPLAY INVISIBLE (-650 4825);
FORCEPROP 1 LAST PATH I28
J 0
(-600 4850);
DISPLAY 0.872340 (-600 4850);
PAINT AQUA (-600 4850);
DISPLAY INVISIBLE (-600 4850);
FORCEADD Q_RES..2
(-650 4575);
FORCEPROP 1 LAST PART_NUMBER CS24702JB10
J 0
(-610 4400);
DISPLAY 0.638298 (-610 4400);
DISPLAY INVISIBLE (-610 4400);
FORCEPROP 1 LAST PACK_TYPE 0402LF
J 0
(-610 4450);
DISPLAY 0.638298 (-610 4450);
FORCEPROP 1 LAST MATERIAL CHIP
J 0
(-610 4500);
DISPLAY 0.638298 (-610 4500);
FORCEPROP 1 LAST WATTAGE 1/16W
J 0
(-610 4550);
DISPLAY 0.638298 (-610 4550);
FORCEPROP 1 LAST TOLERANCE 5%
J 0
(-605 4600);
DISPLAY 0.638298 (-605 4600);
FORCEPROP 1 LAST VALUE 4.7K
J 0
(-605 4650);
DISPLAY 0.638298 (-605 4650);
FORCEPROP 1 LAST $LOCATION R3459
J 0
(-605 4700);
DISPLAY 0.978723 (-605 4700);
FORCEPROP 1 LASTPIN (-650 4675) $PN 1
J 0
(-645 4637);
DISPLAY 0.787234 (-645 4637);
PAINT MONO (-645 4637);
FORCEPROP 1 LASTPIN (-650 4475) $PN 2
J 0
(-645 4485);
DISPLAY 0.787234 (-645 4485);
PAINT MONO (-645 4485);
FORCEPROP 2 LAST CDS_LIB pure_quanta
J 0
(-650 4575);
DISPLAY INVISIBLE (-650 4575);
FORCEPROP 1 LAST PATH I29
J 0
(-600 4750);
DISPLAY 0.978723 (-600 4750);
PAINT WHITE (-600 4750);
DISPLAY INVISIBLE (-600 4750);
FORCEPROP 0 LAST CDS_LOCATION R3459
J 0
(-600 4750);
DISPLAY 1.021277 (-600 4750);
DISPLAY INVISIBLE (-600 4750);
FORCEPROP 0 LAST $SEC 1
J 0
(-600 4750);
DISPLAY 0.680851 (-600 4750);
PAINT MONO (-600 4750);
DISPLAY INVISIBLE (-600 4750);
FORCEPROP 0 LAST CDS_SEC 1
J 0
(-600 4750);
DISPLAY 1.021277 (-600 4750);
DISPLAY INVISIBLE (-600 4750);
FORCEADD UNIVERSAL_GND..1
(-625 3900);
FORCEPROP 3 LASTPIN (-625 3950) SIG_NAME GND\g
J 0
(-615 3960);
DISPLAY 0.659574 (-615 3960);
PAINT MONO (-615 3960);
DISPLAY INVISIBLE (-615 3960);
FORCEPROP 1 LAST PATH I30
J 0
(-550 3900);
DISPLAY 0.872340 (-550 3900);
PAINT AQUA (-550 3900);
DISPLAY INVISIBLE (-550 3900);
FORCEPROP 1 LAST HDL_POWER GND
J 1
(-600 3825);
DISPLAY 0.872340 (-600 3825);
PAINT GREEN (-600 3825);
DISPLAY INVISIBLE (-600 3825);
FORCEPROP 2 LAST CDS_LIB logical_power
J 0
(-625 3900);
DISPLAY INVISIBLE (-625 3900);
FORCEADD Q_RES..2
(-625 4100);
FORCEPROP 1 LAST PART_NUMBER CS41002FB09
J 0
(-585 3975);
DISPLAY 0.510638 (-585 3975);
DISPLAY INVISIBLE (-585 3975);
FORCEPROP 1 LAST TOLERANCE 1%
J 0
(-580 4125);
DISPLAY 0.510638 (-580 4125);
FORCEPROP 1 LAST VALUE 100K
J 0
(-580 4175);
DISPLAY 0.510638 (-580 4175);
FORCEPROP 1 LAST WATTAGE 1/16W
J 0
(-585 4075);
DISPLAY 0.510638 (-585 4075);
FORCEPROP 1 LAST PACK_TYPE 0402LF
J 0
(-585 3925);
DISPLAY 0.510638 (-585 3925);
FORCEPROP 1 LAST MATERIAL EMPTY
J 0
(-585 4025);
DISPLAY 0.510638 (-585 4025);
PAINT RED (-585 4025);
FORCEPROP 1 LAST $LOCATION R3460
J 0
(-580 4225);
DISPLAY 0.978723 (-580 4225);
FORCEPROP 1 LASTPIN (-625 4200) $PN 1
J 0
(-620 4162);
DISPLAY 0.787234 (-620 4162);
PAINT MONO (-620 4162);
FORCEPROP 1 LASTPIN (-625 4000) $PN 2
J 0
(-620 4010);
DISPLAY 0.787234 (-620 4010);
PAINT MONO (-620 4010);
FORCEPROP 1 LAST PATH I31
J 0
(-575 4275);
DISPLAY 0.978723 (-575 4275);
PAINT WHITE (-575 4275);
DISPLAY INVISIBLE (-575 4275);
FORCEPROP 2 LAST CDS_LIB pure_quanta
J 0
(-625 4100);
DISPLAY INVISIBLE (-625 4100);
FORCEPROP 0 LAST CDS_LOCATION R3460
J 0
(-575 4275);
DISPLAY 1.021277 (-575 4275);
DISPLAY INVISIBLE (-575 4275);
FORCEPROP 0 LAST $SEC 1
J 0
(-575 4275);
DISPLAY 0.680851 (-575 4275);
PAINT MONO (-575 4275);
DISPLAY INVISIBLE (-575 4275);
FORCEPROP 0 LAST CDS_SEC 1
J 0
(-575 4275);
DISPLAY 1.021277 (-575 4275);
DISPLAY INVISIBLE (-575 4275);
FORCEADD OFFPAGE..4
R 2
(-900 4300);
FORCEPROP 2 LAST $XR0 213 
J 0
(-1152 4300);
DISPLAY 0.638298 (-1152 4300);
PAINT MONO (-1152 4300);
FORCEPROP 2 LAST CDS_LIB standard
J 0
(-900 4300);
DISPLAY INVISIBLE (-900 4300);
FORCEPROP 1 LAST COMMENT_BODY TRUE
J 2
(-875 4200);
DISPLAY 0.872340 (-875 4200);
PAINT GREEN (-875 4200);
DISPLAY INVISIBLE (-875 4200);
FORCEPROP 1 LAST OFFPAGE TRUE
J 2
(-1225 4175);
DISPLAY 0.872340 (-1225 4175);
PAINT GREEN (-1225 4175);
DISPLAY INVISIBLE (-1225 4175);
FORCEPROP 2 LAST PATH I32
J 0
(-1175 4350);
DISPLAY 1.021277 (-1175 4350);
DISPLAY INVISIBLE (-1175 4350);
FORCEADD Q_RES..2
(1875 4000);
FORCEPROP 1 LAST PART_NUMBER CS41002FB09
J 0
(1915 3875);
DISPLAY 0.510638 (1915 3875);
DISPLAY INVISIBLE (1915 3875);
FORCEPROP 1 LAST PACK_TYPE 0402LF
J 0
(1915 3825);
DISPLAY 0.510638 (1915 3825);
FORCEPROP 1 LAST MATERIAL EMPTY
J 0
(1915 3925);
DISPLAY 0.510638 (1915 3925);
PAINT RED (1915 3925);
FORCEPROP 1 LAST WATTAGE 1/16W
J 0
(1915 3975);
DISPLAY 0.510638 (1915 3975);
FORCEPROP 1 LAST TOLERANCE 1%
J 0
(1920 4025);
DISPLAY 0.510638 (1920 4025);
FORCEPROP 1 LAST VALUE 100K
J 0
(1920 4075);
DISPLAY 0.510638 (1920 4075);
FORCEPROP 1 LAST $LOCATION R3462
J 0
(1920 4125);
DISPLAY 0.978723 (1920 4125);
FORCEPROP 1 LASTPIN (1875 4100) $PN 1
J 0
(1880 4062);
DISPLAY 0.787234 (1880 4062);
PAINT MONO (1880 4062);
FORCEPROP 1 LASTPIN (1875 3900) $PN 2
J 0
(1880 3910);
DISPLAY 0.787234 (1880 3910);
PAINT MONO (1880 3910);
FORCEPROP 2 LAST CDS_LIB pure_quanta
J 0
(1875 4000);
DISPLAY INVISIBLE (1875 4000);
FORCEPROP 1 LAST PATH I33
J 0
(1925 4175);
DISPLAY 0.978723 (1925 4175);
PAINT WHITE (1925 4175);
DISPLAY INVISIBLE (1925 4175);
FORCEPROP 0 LAST CDS_LOCATION R3462
J 0
(1925 4175);
DISPLAY 1.021277 (1925 4175);
DISPLAY INVISIBLE (1925 4175);
FORCEPROP 0 LAST $SEC 1
J 0
(1925 4175);
DISPLAY 0.680851 (1925 4175);
PAINT MONO (1925 4175);
DISPLAY INVISIBLE (1925 4175);
FORCEPROP 0 LAST CDS_SEC 1
J 0
(1925 4175);
DISPLAY 1.021277 (1925 4175);
DISPLAY INVISIBLE (1925 4175);
FORCEADD UNIVERSAL_POWER..1
(1850 4850);
FORCEPROP 3 LASTPIN (1850 4800) SIG_NAME P3V3_AUX\g
J 0
(1860 4810);
DISPLAY 0.659574 (1860 4810);
PAINT MONO (1860 4810);
DISPLAY INVISIBLE (1860 4810);
FORCEPROP 1 LAST HDL_POWER P3V3_AUX
J 1
(1850 4900);
DISPLAY 0.872340 (1850 4900);
PAINT GREEN (1850 4900);
FORCEPROP 2 LAST CDS_LIB logical_power
J 0
(1850 4850);
PAINT MONO (1850 4850);
DISPLAY INVISIBLE (1850 4850);
FORCEPROP 1 LAST PATH I34
J 0
(1900 4875);
DISPLAY 0.872340 (1900 4875);
PAINT AQUA (1900 4875);
DISPLAY INVISIBLE (1900 4875);
FORCEADD Q_RES..2
(1850 4600);
FORCEPROP 1 LAST PART_NUMBER CS35492FB03
J 0
(1890 4475);
DISPLAY 0.787234 (1890 4475);
DISPLAY INVISIBLE (1890 4475);
FORCEPROP 1 LAST WATTAGE 1/16W
J 0
(1890 4575);
DISPLAY 0.787234 (1890 4575);
FORCEPROP 1 LAST VALUE 54.9K
J 0
(1895 4675);
DISPLAY 0.787234 (1895 4675);
FORCEPROP 1 LAST TOLERANCE 1%
J 0
(1895 4625);
DISPLAY 0.787234 (1895 4625);
FORCEPROP 1 LAST MATERIAL CHIP
J 0
(1890 4525);
DISPLAY 0.787234 (1890 4525);
FORCEPROP 1 LAST PACK_TYPE 0402LF
J 0
(1890 4425);
DISPLAY 0.787234 (1890 4425);
FORCEPROP 1 LAST $LOCATION R3461
J 0
(1895 4725);
DISPLAY 0.787234 (1895 4725);
FORCEPROP 1 LASTPIN (1850 4700) $PN 1
J 0
(1855 4662);
DISPLAY 0.787234 (1855 4662);
PAINT MONO (1855 4662);
FORCEPROP 1 LASTPIN (1850 4500) $PN 2
J 0
(1855 4510);
DISPLAY 0.787234 (1855 4510);
PAINT MONO (1855 4510);
FORCEPROP 2 LAST CDS_LIB pure_quanta
J 0
(1850 4600);
DISPLAY INVISIBLE (1850 4600);
FORCEPROP 1 LAST PATH I35
J 0
(1900 4775);
DISPLAY 0.978723 (1900 4775);
PAINT WHITE (1900 4775);
DISPLAY INVISIBLE (1900 4775);
FORCEPROP 0 LAST CDS_LOCATION R3461
J 0
(1900 4775);
DISPLAY 1.021277 (1900 4775);
DISPLAY INVISIBLE (1900 4775);
FORCEPROP 0 LAST $SEC 1
J 0
(1900 4775);
DISPLAY 0.680851 (1900 4775);
PAINT MONO (1900 4775);
DISPLAY INVISIBLE (1900 4775);
FORCEPROP 0 LAST CDS_SEC 1
J 0
(1900 4775);
DISPLAY 1.021277 (1900 4775);
DISPLAY INVISIBLE (1900 4775);
FORCEADD OFFPAGE..2
(3375 4300);
FORCEPROP 2 LAST $XR0 143 
J 0
(3564 4300);
DISPLAY 0.638298 (3564 4300);
PAINT MONO (3564 4300);
FORCEPROP 2 LAST CDS_LIB standard
J 0
(3375 4300);
DISPLAY INVISIBLE (3375 4300);
FORCEPROP 1 LAST OFFPAGE TRUE
J 0
(3700 4175);
DISPLAY 0.872340 (3700 4175);
PAINT AQUA (3700 4175);
DISPLAY INVISIBLE (3700 4175);
FORCEPROP 1 LAST COMMENT_BODY TRUE
J 0
(3330 4205);
DISPLAY 0.872340 (3330 4205);
PAINT GREEN (3330 4205);
DISPLAY INVISIBLE (3330 4205);
FORCEPROP 2 LAST PATH I36
J 0
(3575 4350);
DISPLAY 1.021277 (3575 4350);
DISPLAY INVISIBLE (3575 4350);
FORCEADD Q_RES..1
(2100 4300);
FORCEPROP 1 LAST PART_NUMBER CS03322FB03
J 0
(1700 4200);
DISPLAY 0.723404 (1700 4200);
PAINT WHITE (1700 4200);
DISPLAY INVISIBLE (1700 4200);
FORCEPROP 1 LAST VALUE 33.2
J 2
(2350 4300);
DISPLAY 0.723404 (2350 4300);
FORCEPROP 1 LAST PACK_TYPE 0402LF
J 0
(1925 4250);
DISPLAY 0.723404 (1925 4250);
FORCEPROP 1 LAST MATERIAL CHIP
J 0
(2125 4250);
DISPLAY 0.723404 (2125 4250);
FORCEPROP 1 LAST $LOCATION R3397
J 0
(1900 4300);
DISPLAY 0.723404 (1900 4300);
FORCEPROP 1 LASTPIN (2000 4300) $PN 1
J 0
(2012 4312);
DISPLAY 0.723404 (2012 4312);
PAINT MONO (2012 4312);
FORCEPROP 1 LASTPIN (2200 4300) $PN 2
J 0
(2162 4312);
DISPLAY 0.723404 (2162 4312);
PAINT MONO (2162 4312);
FORCEPROP 2 LAST CDS_LIB pure_quanta
J 0
(2100 4300);
DISPLAY INVISIBLE (2100 4300);
FORCEPROP 1 LAST TOLERANCE 1%
J 0
(2575 4300);
DISPLAY 0.723404 (2575 4300);
PAINT SKYBLUE (2575 4300);
DISPLAY INVISIBLE (2575 4300);
FORCEPROP 1 LAST WATTAGE 1/16W
J 2
(2500 4250);
DISPLAY 0.723404 (2500 4250);
PAINT SKYBLUE (2500 4250);
DISPLAY INVISIBLE (2500 4250);
FORCEPROP 1 LAST PATH I37
J 0
(2050 4450);
DISPLAY 0.978723 (2050 4450);
PAINT WHITE (2050 4450);
DISPLAY INVISIBLE (2050 4450);
FORCEPROP 2 LAST CDS_LOCATION R3397
J 0
(2050 4500);
DISPLAY 1.021277 (2050 4500);
DISPLAY INVISIBLE (2050 4500);
FORCEPROP 2 LAST $SEC 1
J 0
(2050 4500);
DISPLAY 0.680851 (2050 4500);
PAINT MONO (2050 4500);
DISPLAY INVISIBLE (2050 4500);
FORCEPROP 0 LAST CDS_SEC 1
J 0
(1800 4375);
DISPLAY INVISIBLE (1800 4375);
FORCEADD UNIVERSAL_GND..1
(1875 3800);
FORCEPROP 3 LASTPIN (1875 3850) SIG_NAME GND\g
J 0
(1885 3860);
DISPLAY 0.659574 (1885 3860);
PAINT MONO (1885 3860);
DISPLAY INVISIBLE (1885 3860);
FORCEPROP 2 LAST CDS_LIB logical_power
J 0
(1875 3800);
DISPLAY INVISIBLE (1875 3800);
FORCEPROP 1 LAST HDL_POWER GND
J 1
(1900 3725);
DISPLAY 0.872340 (1900 3725);
PAINT GREEN (1900 3725);
DISPLAY INVISIBLE (1900 3725);
FORCEPROP 1 LAST PATH I38
J 0
(1950 3800);
DISPLAY 0.872340 (1950 3800);
PAINT AQUA (1950 3800);
DISPLAY INVISIBLE (1950 3800);
FORCEADD UNIVERSAL_POWER..1
(-650 3675);
FORCEPROP 3 LASTPIN (-650 3625) SIG_NAME P3V3_AUX\g
J 0
(-640 3635);
DISPLAY 0.659574 (-640 3635);
PAINT MONO (-640 3635);
DISPLAY INVISIBLE (-640 3635);
FORCEPROP 1 LAST HDL_POWER P3V3_AUX
J 1
(-650 3725);
DISPLAY 0.872340 (-650 3725);
PAINT GREEN (-650 3725);
FORCEPROP 2 LAST CDS_LIB logical_power
J 0
(-650 3675);
PAINT MONO (-650 3675);
DISPLAY INVISIBLE (-650 3675);
FORCEPROP 1 LAST PATH I39
J 0
(-600 3700);
DISPLAY 0.872340 (-600 3700);
PAINT AQUA (-600 3700);
DISPLAY INVISIBLE (-600 3700);
FORCEADD Q_RES..2
(-650 3425);
FORCEPROP 1 LAST PART_NUMBER CS24702JB10
J 0
(-610 3250);
DISPLAY 0.638298 (-610 3250);
DISPLAY INVISIBLE (-610 3250);
FORCEPROP 1 LAST WATTAGE 1/16W
J 0
(-610 3400);
DISPLAY 0.638298 (-610 3400);
FORCEPROP 1 LAST VALUE 4.7K
J 0
(-605 3500);
DISPLAY 0.638298 (-605 3500);
FORCEPROP 1 LAST TOLERANCE 5%
J 0
(-605 3450);
DISPLAY 0.638298 (-605 3450);
FORCEPROP 1 LAST MATERIAL CHIP
J 0
(-610 3350);
DISPLAY 0.638298 (-610 3350);
FORCEPROP 1 LAST PACK_TYPE 0402LF
J 0
(-610 3300);
DISPLAY 0.638298 (-610 3300);
FORCEPROP 1 LAST $LOCATION R3488
J 0
(-605 3550);
DISPLAY 0.978723 (-605 3550);
FORCEPROP 1 LASTPIN (-650 3525) $PN 1
J 0
(-645 3487);
DISPLAY 0.787234 (-645 3487);
PAINT MONO (-645 3487);
FORCEPROP 1 LASTPIN (-650 3325) $PN 2
J 0
(-645 3335);
DISPLAY 0.787234 (-645 3335);
PAINT MONO (-645 3335);
FORCEPROP 2 LAST CDS_LIB pure_quanta
J 0
(-650 3425);
DISPLAY INVISIBLE (-650 3425);
FORCEPROP 1 LAST PATH I40
J 0
(-600 3600);
DISPLAY 0.978723 (-600 3600);
PAINT WHITE (-600 3600);
DISPLAY INVISIBLE (-600 3600);
FORCEPROP 0 LAST CDS_LOCATION R3488
J 0
(-600 3600);
DISPLAY 1.021277 (-600 3600);
DISPLAY INVISIBLE (-600 3600);
FORCEPROP 0 LAST $SEC 1
J 0
(-600 3600);
DISPLAY 0.680851 (-600 3600);
PAINT MONO (-600 3600);
DISPLAY INVISIBLE (-600 3600);
FORCEPROP 0 LAST CDS_SEC 1
J 0
(-600 3600);
DISPLAY 1.021277 (-600 3600);
DISPLAY INVISIBLE (-600 3600);
FORCEADD OFFPAGE..4
R 2
(-900 3150);
FORCEPROP 2 LAST $XR0 213 
J 0
(-1152 3150);
DISPLAY 0.638298 (-1152 3150);
PAINT MONO (-1152 3150);
FORCEPROP 1 LAST OFFPAGE TRUE
J 2
(-1225 3025);
DISPLAY 0.872340 (-1225 3025);
PAINT GREEN (-1225 3025);
DISPLAY INVISIBLE (-1225 3025);
FORCEPROP 1 LAST COMMENT_BODY TRUE
J 2
(-875 3050);
DISPLAY 0.872340 (-875 3050);
PAINT GREEN (-875 3050);
DISPLAY INVISIBLE (-875 3050);
FORCEPROP 2 LAST CDS_LIB standard
J 0
(-900 3150);
DISPLAY INVISIBLE (-900 3150);
FORCEPROP 2 LAST PATH I41
J 0
(-1150 3200);
DISPLAY 1.021277 (-1150 3200);
DISPLAY INVISIBLE (-1150 3200);
FORCEADD Q_RES..2
(-625 2950);
FORCEPROP 1 LAST PART_NUMBER CS41002FB09
J 0
(-585 2825);
DISPLAY 0.510638 (-585 2825);
DISPLAY INVISIBLE (-585 2825);
FORCEPROP 1 LAST MATERIAL EMPTY
J 0
(-585 2875);
DISPLAY 0.510638 (-585 2875);
PAINT RED (-585 2875);
FORCEPROP 1 LAST PACK_TYPE 0402LF
J 0
(-585 2775);
DISPLAY 0.510638 (-585 2775);
FORCEPROP 1 LAST WATTAGE 1/16W
J 0
(-585 2925);
DISPLAY 0.510638 (-585 2925);
FORCEPROP 1 LAST VALUE 100K
J 0
(-580 3025);
DISPLAY 0.510638 (-580 3025);
FORCEPROP 1 LAST TOLERANCE 1%
J 0
(-580 2975);
DISPLAY 0.510638 (-580 2975);
FORCEPROP 1 LAST $LOCATION R3489
J 0
(-580 3075);
DISPLAY 0.978723 (-580 3075);
FORCEPROP 1 LASTPIN (-625 3050) $PN 1
J 0
(-620 3012);
DISPLAY 0.787234 (-620 3012);
PAINT MONO (-620 3012);
FORCEPROP 1 LASTPIN (-625 2850) $PN 2
J 0
(-620 2860);
DISPLAY 0.787234 (-620 2860);
PAINT MONO (-620 2860);
FORCEPROP 1 LAST PATH I42
J 0
(-575 3125);
DISPLAY 0.978723 (-575 3125);
PAINT WHITE (-575 3125);
DISPLAY INVISIBLE (-575 3125);
FORCEPROP 2 LAST CDS_LIB pure_quanta
J 0
(-625 2950);
DISPLAY INVISIBLE (-625 2950);
FORCEPROP 0 LAST CDS_LOCATION R3489
J 0
(-575 3125);
DISPLAY 1.021277 (-575 3125);
DISPLAY INVISIBLE (-575 3125);
FORCEPROP 0 LAST $SEC 1
J 0
(-575 3125);
DISPLAY 0.680851 (-575 3125);
PAINT MONO (-575 3125);
DISPLAY INVISIBLE (-575 3125);
FORCEPROP 0 LAST CDS_SEC 1
J 0
(-575 3125);
DISPLAY 1.021277 (-575 3125);
DISPLAY INVISIBLE (-575 3125);
FORCEADD UNIVERSAL_GND..1
(-625 2750);
FORCEPROP 3 LASTPIN (-625 2800) SIG_NAME GND\g
J 0
(-615 2810);
DISPLAY 0.659574 (-615 2810);
PAINT MONO (-615 2810);
DISPLAY INVISIBLE (-615 2810);
FORCEPROP 1 LAST PATH I43
J 0
(-550 2750);
DISPLAY 0.872340 (-550 2750);
PAINT AQUA (-550 2750);
DISPLAY INVISIBLE (-550 2750);
FORCEPROP 2 LAST CDS_LIB logical_power
J 0
(-625 2750);
DISPLAY INVISIBLE (-625 2750);
FORCEPROP 1 LAST HDL_POWER GND
J 1
(-600 2675);
DISPLAY 0.872340 (-600 2675);
PAINT GREEN (-600 2675);
DISPLAY INVISIBLE (-600 2675);
FORCEADD OFFPAGE..2
(3425 3100);
FORCEPROP 2 LAST $XR0 141 
J 0
(3614 3100);
DISPLAY 0.638298 (3614 3100);
PAINT MONO (3614 3100);
FORCEPROP 2 LAST CDS_LIB standard
J 0
(3425 3100);
DISPLAY INVISIBLE (3425 3100);
FORCEPROP 1 LAST OFFPAGE TRUE
J 0
(3750 2975);
DISPLAY 0.872340 (3750 2975);
PAINT AQUA (3750 2975);
DISPLAY INVISIBLE (3750 2975);
FORCEPROP 1 LAST COMMENT_BODY TRUE
J 0
(3380 3005);
DISPLAY 0.872340 (3380 3005);
PAINT GREEN (3380 3005);
DISPLAY INVISIBLE (3380 3005);
FORCEPROP 2 LAST PATH I44
J 0
(3600 3175);
DISPLAY 1.021277 (3600 3175);
DISPLAY INVISIBLE (3600 3175);
FORCEADD Q_RES..1
(2150 3100);
FORCEPROP 1 LAST PART_NUMBER CS03322FB03
J 0
(1750 3000);
DISPLAY 0.723404 (1750 3000);
PAINT WHITE (1750 3000);
DISPLAY INVISIBLE (1750 3000);
FORCEPROP 1 LAST VALUE 33.2
J 2
(2400 3100);
DISPLAY 0.723404 (2400 3100);
FORCEPROP 1 LAST PACK_TYPE 0402LF
J 0
(1975 3050);
DISPLAY 0.723404 (1975 3050);
FORCEPROP 1 LAST MATERIAL CHIP
J 0
(2175 3050);
DISPLAY 0.723404 (2175 3050);
FORCEPROP 1 LAST $LOCATION R3496
J 0
(1925 3100);
DISPLAY 0.723404 (1925 3100);
FORCEPROP 1 LASTPIN (2050 3100) $PN 1
J 0
(2062 3112);
DISPLAY 0.723404 (2062 3112);
PAINT MONO (2062 3112);
FORCEPROP 1 LASTPIN (2250 3100) $PN 2
J 0
(2212 3112);
DISPLAY 0.723404 (2212 3112);
PAINT MONO (2212 3112);
FORCEPROP 2 LAST CDS_LIB pure_quanta
J 0
(2150 3100);
DISPLAY INVISIBLE (2150 3100);
FORCEPROP 1 LAST TOLERANCE 1%
J 0
(2625 3100);
DISPLAY 0.723404 (2625 3100);
PAINT SKYBLUE (2625 3100);
DISPLAY INVISIBLE (2625 3100);
FORCEPROP 1 LAST WATTAGE 1/16W
J 2
(2550 3050);
DISPLAY 0.723404 (2550 3050);
PAINT SKYBLUE (2550 3050);
DISPLAY INVISIBLE (2550 3050);
FORCEPROP 1 LAST PATH I45
J 0
(2100 3250);
DISPLAY 0.978723 (2100 3250);
PAINT WHITE (2100 3250);
DISPLAY INVISIBLE (2100 3250);
FORCEPROP 2 LAST CDS_LOCATION R3496
J 0
(2100 3300);
DISPLAY 1.021277 (2100 3300);
DISPLAY INVISIBLE (2100 3300);
FORCEPROP 2 LAST $SEC 1
J 0
(2100 3300);
DISPLAY 0.680851 (2100 3300);
PAINT MONO (2100 3300);
DISPLAY INVISIBLE (2100 3300);
FORCEPROP 0 LAST CDS_SEC 1
J 0
(1850 3175);
DISPLAY INVISIBLE (1850 3175);
FORCEADD UNIVERSAL_POWER..1
(1900 3650);
FORCEPROP 3 LASTPIN (1900 3600) SIG_NAME P3V3_AUX\g
J 0
(1910 3610);
DISPLAY 0.659574 (1910 3610);
PAINT MONO (1910 3610);
DISPLAY INVISIBLE (1910 3610);
FORCEPROP 1 LAST HDL_POWER P3V3_AUX
J 1
(1900 3700);
DISPLAY 0.872340 (1900 3700);
PAINT GREEN (1900 3700);
FORCEPROP 2 LAST CDS_LIB logical_power
J 0
(1900 3650);
PAINT MONO (1900 3650);
DISPLAY INVISIBLE (1900 3650);
FORCEPROP 1 LAST PATH I46
J 0
(1950 3675);
DISPLAY 0.872340 (1950 3675);
PAINT AQUA (1950 3675);
DISPLAY INVISIBLE (1950 3675);
FORCEADD Q_RES..2
(1900 3400);
FORCEPROP 1 LAST PART_NUMBER CS35492FB03
J 0
(1940 3275);
DISPLAY 0.787234 (1940 3275);
DISPLAY INVISIBLE (1940 3275);
FORCEPROP 1 LAST WATTAGE 1/16W
J 0
(1940 3375);
DISPLAY 0.787234 (1940 3375);
FORCEPROP 1 LAST VALUE 54.9K
J 0
(1945 3475);
DISPLAY 0.787234 (1945 3475);
FORCEPROP 1 LAST TOLERANCE 1%
J 0
(1945 3425);
DISPLAY 0.787234 (1945 3425);
FORCEPROP 1 LAST MATERIAL CHIP
J 0
(1940 3325);
DISPLAY 0.787234 (1940 3325);
FORCEPROP 1 LAST PACK_TYPE 0402LF
J 0
(1940 3225);
DISPLAY 0.787234 (1940 3225);
FORCEPROP 1 LAST $LOCATION R3492
J 0
(1945 3525);
DISPLAY 0.787234 (1945 3525);
FORCEPROP 1 LASTPIN (1900 3500) $PN 1
J 0
(1905 3462);
DISPLAY 0.787234 (1905 3462);
PAINT MONO (1905 3462);
FORCEPROP 1 LASTPIN (1900 3300) $PN 2
J 0
(1905 3310);
DISPLAY 0.787234 (1905 3310);
PAINT MONO (1905 3310);
FORCEPROP 2 LAST CDS_LIB pure_quanta
J 0
(1900 3400);
DISPLAY INVISIBLE (1900 3400);
FORCEPROP 1 LAST PATH I47
J 0
(1950 3575);
DISPLAY 0.978723 (1950 3575);
PAINT WHITE (1950 3575);
DISPLAY INVISIBLE (1950 3575);
FORCEPROP 0 LAST CDS_LOCATION R3492
J 0
(1950 3575);
DISPLAY 1.021277 (1950 3575);
DISPLAY INVISIBLE (1950 3575);
FORCEPROP 0 LAST $SEC 1
J 0
(1950 3575);
DISPLAY 0.680851 (1950 3575);
PAINT MONO (1950 3575);
DISPLAY INVISIBLE (1950 3575);
FORCEPROP 0 LAST CDS_SEC 1
J 0
(1950 3575);
DISPLAY 1.021277 (1950 3575);
DISPLAY INVISIBLE (1950 3575);
FORCEADD Q_RES..2
(1925 2800);
FORCEPROP 1 LAST PART_NUMBER CS41002FB09
J 0
(1965 2675);
DISPLAY 0.510638 (1965 2675);
DISPLAY INVISIBLE (1965 2675);
FORCEPROP 1 LAST WATTAGE 1/16W
J 0
(1965 2775);
DISPLAY 0.510638 (1965 2775);
FORCEPROP 1 LAST TOLERANCE 1%
J 0
(1970 2825);
DISPLAY 0.510638 (1970 2825);
FORCEPROP 1 LAST VALUE 100K
J 0
(1970 2875);
DISPLAY 0.510638 (1970 2875);
FORCEPROP 1 LAST MATERIAL EMPTY
J 0
(1965 2725);
DISPLAY 0.510638 (1965 2725);
PAINT RED (1965 2725);
FORCEPROP 1 LAST PACK_TYPE 0402LF
J 0
(1965 2625);
DISPLAY 0.510638 (1965 2625);
FORCEPROP 1 LAST $LOCATION R3493
J 0
(1970 2925);
DISPLAY 0.978723 (1970 2925);
FORCEPROP 1 LASTPIN (1925 2900) $PN 1
J 0
(1930 2862);
DISPLAY 0.787234 (1930 2862);
PAINT MONO (1930 2862);
FORCEPROP 1 LASTPIN (1925 2700) $PN 2
J 0
(1930 2710);
DISPLAY 0.787234 (1930 2710);
PAINT MONO (1930 2710);
FORCEPROP 2 LAST CDS_LIB pure_quanta
J 0
(1925 2800);
DISPLAY INVISIBLE (1925 2800);
FORCEPROP 1 LAST PATH I48
J 0
(1975 2975);
DISPLAY 0.978723 (1975 2975);
PAINT WHITE (1975 2975);
DISPLAY INVISIBLE (1975 2975);
FORCEPROP 0 LAST CDS_LOCATION R3493
J 0
(1975 2975);
DISPLAY 1.021277 (1975 2975);
DISPLAY INVISIBLE (1975 2975);
FORCEPROP 0 LAST $SEC 1
J 0
(1975 2975);
DISPLAY 0.680851 (1975 2975);
PAINT MONO (1975 2975);
DISPLAY INVISIBLE (1975 2975);
FORCEPROP 0 LAST CDS_SEC 1
J 0
(1975 2975);
DISPLAY 1.021277 (1975 2975);
DISPLAY INVISIBLE (1975 2975);
FORCEADD UNIVERSAL_GND..1
(1925 2600);
FORCEPROP 3 LASTPIN (1925 2650) SIG_NAME GND\g
J 0
(1935 2660);
DISPLAY 0.659574 (1935 2660);
PAINT MONO (1935 2660);
DISPLAY INVISIBLE (1935 2660);
FORCEPROP 2 LAST CDS_LIB logical_power
J 0
(1925 2600);
DISPLAY INVISIBLE (1925 2600);
FORCEPROP 1 LAST HDL_POWER GND
J 1
(1950 2525);
DISPLAY 0.872340 (1950 2525);
PAINT GREEN (1950 2525);
DISPLAY INVISIBLE (1950 2525);
FORCEPROP 1 LAST PATH I49
J 0
(2000 2600);
DISPLAY 0.872340 (2000 2600);
PAINT AQUA (2000 2600);
DISPLAY INVISIBLE (2000 2600);
FORCEADD 74LVC2G07DW7..1
(775 1250);
FORCEPROP 1 LAST PART_NUMBER AL002G07003
J 0
(606 1484);
DISPLAY 0.723404 (606 1484);
PAINT GREEN (606 1484);
DISPLAY INVISIBLE (606 1484);
FORCEPROP 2 LAST PART_TYPE SMLF
J 0
(625 1725);
DISPLAY 1.021277 (625 1725);
FORCEPROP 2 LAST VALUE 74LVC2G07DW-7
J 0
(475 1550);
DISPLAY 1.021277 (475 1550);
FORCEPROP 1 LAST MATERIAL IC
J 0
(606 1357);
DISPLAY 0.723404 (606 1357);
PAINT GREEN (606 1357);
FORCEPROP 1 LAST $LOCATION U257
J 0
(606 1631);
DISPLAY 0.723404 (606 1631);
PAINT GREEN (606 1631);
FORCEPROP 0 LASTPIN (450 1300) $PN 1
J 2
(440 1310);
DISPLAY 0.680851 (440 1310);
PAINT MONO (440 1310);
FORCEPROP 0 LASTPIN (1100 1300) $PN 6
J 0
(1110 1310);
DISPLAY 0.680851 (1110 1310);
PAINT MONO (1110 1310);
FORCEPROP 0 LASTPIN (450 1200) $PN 3
J 2
(440 1210);
DISPLAY 0.680851 (440 1210);
PAINT MONO (440 1210);
FORCEPROP 0 LASTPIN (1100 1200) $PN 4
J 0
(1110 1210);
DISPLAY 0.680851 (1110 1210);
PAINT MONO (1110 1210);
FORCEPROP 0 LASTPIN (450 1250) $PN 2
J 2
(440 1260);
DISPLAY 0.680851 (440 1260);
PAINT MONO (440 1260);
FORCEPROP 0 LASTPIN (1100 1250) $PN 5
J 0
(1110 1260);
DISPLAY 0.680851 (1110 1260);
PAINT MONO (1110 1260);
FORCEPROP 1 LAST PATH I50
J 0
(775 1250);
DISPLAY 0.723404 (775 1250);
PAINT GREEN (775 1250);
DISPLAY INVISIBLE (775 1250);
FORCEPROP 2 LAST CDS_LIB pure_quanta
J 0
(775 1250);
DISPLAY INVISIBLE (775 1250);
FORCEPROP 1 LAST NEEDS_NO_SIZE TRUE
J 0
(775 1250);
DISPLAY 0.723404 (775 1250);
PAINT GREEN (775 1250);
DISPLAY INVISIBLE (775 1250);
FORCEPROP 1 LAST CDS_LMAN_SYM_OUTLINE -175,100,175,-100
J 0
(775 1250);
DISPLAY 0.468085 (775 1250);
PAINT GREEN (775 1250);
DISPLAY INVISIBLE (775 1250);
FORCEPROP 0 LAST CDS_LOCATION U257
J 0
(625 1775);
DISPLAY 1.021277 (625 1775);
DISPLAY INVISIBLE (625 1775);
FORCEPROP 0 LAST $SEC 1
J 0
(625 1775);
DISPLAY 0.680851 (625 1775);
PAINT MONO (625 1775);
DISPLAY INVISIBLE (625 1775);
FORCEPROP 0 LAST CDS_SEC 1
J 0
(625 1775);
DISPLAY 1.021277 (625 1775);
DISPLAY INVISIBLE (625 1775);
FORCEADD OFFPAGE..2
(3600 1800);
FORCEPROP 2 LAST $XR0 141 
J 0
(3789 1800);
DISPLAY 0.638298 (3789 1800);
PAINT MONO (3789 1800);
FORCEPROP 2 LAST PATH I51
J 0
(3775 1875);
DISPLAY 1.021277 (3775 1875);
DISPLAY INVISIBLE (3775 1875);
FORCEPROP 2 LAST CDS_LIB standard
J 0
(3600 1800);
DISPLAY INVISIBLE (3600 1800);
FORCEPROP 1 LAST OFFPAGE TRUE
J 0
(3925 1675);
DISPLAY 0.872340 (3925 1675);
PAINT AQUA (3925 1675);
DISPLAY INVISIBLE (3925 1675);
FORCEPROP 1 LAST COMMENT_BODY TRUE
J 0
(3555 1705);
DISPLAY 0.872340 (3555 1705);
PAINT GREEN (3555 1705);
DISPLAY INVISIBLE (3555 1705);
FORCEADD Q_RES..1
(2325 1800);
FORCEPROP 1 LAST PART_NUMBER CS03322FB03
J 0
(1925 1700);
DISPLAY 0.723404 (1925 1700);
PAINT WHITE (1925 1700);
DISPLAY INVISIBLE (1925 1700);
FORCEPROP 1 LAST VALUE 33.2
J 2
(2575 1800);
DISPLAY 0.723404 (2575 1800);
FORCEPROP 1 LAST PACK_TYPE 0402LF
J 0
(2150 1750);
DISPLAY 0.723404 (2150 1750);
FORCEPROP 1 LAST MATERIAL CHIP
J 0
(2350 1750);
DISPLAY 0.723404 (2350 1750);
FORCEPROP 1 LAST $LOCATION R3497
J 0
(2125 1800);
DISPLAY 0.723404 (2125 1800);
FORCEPROP 1 LASTPIN (2225 1800) $PN 1
J 0
(2237 1812);
DISPLAY 0.723404 (2237 1812);
PAINT MONO (2237 1812);
FORCEPROP 1 LASTPIN (2425 1800) $PN 2
J 0
(2387 1812);
DISPLAY 0.723404 (2387 1812);
PAINT MONO (2387 1812);
FORCEPROP 1 LAST PATH I53
J 0
(2275 1950);
DISPLAY 0.978723 (2275 1950);
PAINT WHITE (2275 1950);
DISPLAY INVISIBLE (2275 1950);
FORCEPROP 2 LAST CDS_LIB pure_quanta
J 0
(2325 1800);
DISPLAY INVISIBLE (2325 1800);
FORCEPROP 1 LAST TOLERANCE 1%
J 0
(2800 1800);
DISPLAY 0.723404 (2800 1800);
PAINT SKYBLUE (2800 1800);
DISPLAY INVISIBLE (2800 1800);
FORCEPROP 1 LAST WATTAGE 1/16W
J 2
(2725 1750);
DISPLAY 0.723404 (2725 1750);
PAINT SKYBLUE (2725 1750);
DISPLAY INVISIBLE (2725 1750);
FORCEPROP 2 LAST CDS_LOCATION R3497
J 0
(2275 2000);
DISPLAY 1.021277 (2275 2000);
DISPLAY INVISIBLE (2275 2000);
FORCEPROP 2 LAST $SEC 1
J 0
(2275 2000);
DISPLAY 0.680851 (2275 2000);
PAINT MONO (2275 2000);
DISPLAY INVISIBLE (2275 2000);
FORCEPROP 0 LAST CDS_SEC 1
J 0
(2025 1875);
DISPLAY INVISIBLE (2025 1875);
FORCEADD UNIVERSAL_POWER..1
(2075 2350);
FORCEPROP 3 LASTPIN (2075 2300) SIG_NAME P3V3_AUX\g
J 0
(2085 2310);
DISPLAY 0.659574 (2085 2310);
PAINT MONO (2085 2310);
DISPLAY INVISIBLE (2085 2310);
FORCEPROP 1 LAST HDL_POWER P3V3_AUX
J 1
(2075 2400);
DISPLAY 0.872340 (2075 2400);
PAINT GREEN (2075 2400);
FORCEPROP 1 LAST PATH I54
J 0
(2125 2375);
DISPLAY 0.872340 (2125 2375);
PAINT AQUA (2125 2375);
DISPLAY INVISIBLE (2125 2375);
FORCEPROP 2 LAST CDS_LIB logical_power
J 0
(2075 2350);
PAINT MONO (2075 2350);
DISPLAY INVISIBLE (2075 2350);
FORCEADD Q_RES..2
(2075 2100);
FORCEPROP 1 LAST PART_NUMBER CS35492FB03
J 0
(2115 1975);
DISPLAY 0.787234 (2115 1975);
DISPLAY INVISIBLE (2115 1975);
FORCEPROP 1 LAST PACK_TYPE 0402LF
J 0
(2115 1925);
DISPLAY 0.787234 (2115 1925);
FORCEPROP 1 LAST TOLERANCE 1%
J 0
(2120 2125);
DISPLAY 0.787234 (2120 2125);
FORCEPROP 1 LAST WATTAGE 1/16W
J 0
(2115 2075);
DISPLAY 0.787234 (2115 2075);
FORCEPROP 1 LAST MATERIAL CHIP
J 0
(2115 2025);
DISPLAY 0.787234 (2115 2025);
FORCEPROP 1 LAST VALUE 54.9K
J 0
(2120 2175);
DISPLAY 0.787234 (2120 2175);
FORCEPROP 1 LAST $LOCATION R3494
J 0
(2120 2225);
DISPLAY 0.787234 (2120 2225);
FORCEPROP 1 LASTPIN (2075 2200) $PN 1
J 0
(2080 2162);
DISPLAY 0.787234 (2080 2162);
PAINT MONO (2080 2162);
FORCEPROP 1 LASTPIN (2075 2000) $PN 2
J 0
(2080 2010);
DISPLAY 0.787234 (2080 2010);
PAINT MONO (2080 2010);
FORCEPROP 1 LAST PATH I55
J 0
(2125 2275);
DISPLAY 0.978723 (2125 2275);
PAINT WHITE (2125 2275);
DISPLAY INVISIBLE (2125 2275);
FORCEPROP 2 LAST CDS_LIB pure_quanta
J 0
(2075 2100);
DISPLAY INVISIBLE (2075 2100);
FORCEPROP 0 LAST CDS_LOCATION R3494
J 0
(2125 2275);
DISPLAY 1.021277 (2125 2275);
DISPLAY INVISIBLE (2125 2275);
FORCEPROP 0 LAST $SEC 1
J 0
(2125 2275);
DISPLAY 0.680851 (2125 2275);
PAINT MONO (2125 2275);
DISPLAY INVISIBLE (2125 2275);
FORCEPROP 0 LAST CDS_SEC 1
J 0
(2125 2275);
DISPLAY 1.021277 (2125 2275);
DISPLAY INVISIBLE (2125 2275);
FORCEADD UNIVERSAL_POWER..1
(-650 2325);
FORCEPROP 3 LASTPIN (-650 2275) SIG_NAME P3V3_AUX\g
J 0
(-640 2285);
DISPLAY 0.659574 (-640 2285);
PAINT MONO (-640 2285);
DISPLAY INVISIBLE (-640 2285);
FORCEPROP 1 LAST HDL_POWER P3V3_AUX
J 1
(-650 2375);
DISPLAY 0.872340 (-650 2375);
PAINT GREEN (-650 2375);
FORCEPROP 1 LAST PATH I56
J 0
(-600 2350);
DISPLAY 0.872340 (-600 2350);
PAINT AQUA (-600 2350);
DISPLAY INVISIBLE (-600 2350);
FORCEPROP 2 LAST CDS_LIB logical_power
J 0
(-650 2325);
PAINT MONO (-650 2325);
DISPLAY INVISIBLE (-650 2325);
FORCEADD Q_RES..2
(-650 2075);
FORCEPROP 1 LAST PART_NUMBER CS24702JB10
J 0
(-610 1900);
DISPLAY 0.638298 (-610 1900);
DISPLAY INVISIBLE (-610 1900);
FORCEPROP 1 LAST PACK_TYPE 0402LF
J 0
(-610 1950);
DISPLAY 0.638298 (-610 1950);
FORCEPROP 1 LAST TOLERANCE 5%
J 0
(-605 2100);
DISPLAY 0.638298 (-605 2100);
FORCEPROP 1 LAST WATTAGE 1/16W
J 0
(-610 2050);
DISPLAY 0.638298 (-610 2050);
FORCEPROP 1 LAST MATERIAL CHIP
J 0
(-610 2000);
DISPLAY 0.638298 (-610 2000);
FORCEPROP 1 LAST VALUE 4.7K
J 0
(-605 2150);
DISPLAY 0.638298 (-605 2150);
FORCEPROP 1 LAST $LOCATION R3490
J 0
(-605 2200);
DISPLAY 0.978723 (-605 2200);
FORCEPROP 1 LASTPIN (-650 2175) $PN 1
J 0
(-645 2137);
DISPLAY 0.787234 (-645 2137);
PAINT MONO (-645 2137);
FORCEPROP 1 LASTPIN (-650 1975) $PN 2
J 0
(-645 1985);
DISPLAY 0.787234 (-645 1985);
PAINT MONO (-645 1985);
FORCEPROP 1 LAST PATH I57
J 0
(-600 2250);
DISPLAY 0.978723 (-600 2250);
PAINT WHITE (-600 2250);
DISPLAY INVISIBLE (-600 2250);
FORCEPROP 2 LAST CDS_LIB pure_quanta
J 0
(-650 2075);
DISPLAY INVISIBLE (-650 2075);
FORCEPROP 0 LAST CDS_LOCATION R3490
J 0
(-600 2250);
DISPLAY 1.021277 (-600 2250);
DISPLAY INVISIBLE (-600 2250);
FORCEPROP 0 LAST $SEC 1
J 0
(-600 2250);
DISPLAY 0.680851 (-600 2250);
PAINT MONO (-600 2250);
DISPLAY INVISIBLE (-600 2250);
FORCEPROP 0 LAST CDS_SEC 1
J 0
(-600 2250);
DISPLAY 1.021277 (-600 2250);
DISPLAY INVISIBLE (-600 2250);
FORCEADD OFFPAGE..4
R 2
(-900 1800);
FORCEPROP 2 LAST $XR0 213 
J 0
(-1152 1800);
DISPLAY 0.638298 (-1152 1800);
PAINT MONO (-1152 1800);
FORCEPROP 2 LAST CDS_LIB standard
J 0
(-900 1800);
DISPLAY INVISIBLE (-900 1800);
FORCEPROP 2 LAST PATH I58
J 0
(-1150 1850);
DISPLAY 1.021277 (-1150 1850);
DISPLAY INVISIBLE (-1150 1850);
FORCEPROP 1 LAST COMMENT_BODY TRUE
J 2
(-875 1700);
DISPLAY 0.872340 (-875 1700);
PAINT GREEN (-875 1700);
DISPLAY INVISIBLE (-875 1700);
FORCEPROP 1 LAST OFFPAGE TRUE
J 2
(-1225 1675);
DISPLAY 0.872340 (-1225 1675);
PAINT GREEN (-1225 1675);
DISPLAY INVISIBLE (-1225 1675);
FORCEADD Q_RES..2
(2100 1500);
FORCEPROP 1 LAST PART_NUMBER CS41002FB09
J 0
(2140 1375);
DISPLAY 0.510638 (2140 1375);
DISPLAY INVISIBLE (2140 1375);
FORCEPROP 1 LAST VALUE 100K
J 0
(2145 1575);
DISPLAY 0.510638 (2145 1575);
FORCEPROP 1 LAST PACK_TYPE 0402LF
J 0
(2140 1325);
DISPLAY 0.510638 (2140 1325);
FORCEPROP 1 LAST WATTAGE 1/16W
J 0
(2140 1475);
DISPLAY 0.510638 (2140 1475);
FORCEPROP 1 LAST TOLERANCE 1%
J 0
(2145 1525);
DISPLAY 0.510638 (2145 1525);
FORCEPROP 1 LAST MATERIAL EMPTY
J 0
(2140 1425);
DISPLAY 0.510638 (2140 1425);
PAINT RED (2140 1425);
FORCEPROP 1 LAST $LOCATION R3495
J 0
(2145 1625);
DISPLAY 0.978723 (2145 1625);
FORCEPROP 1 LASTPIN (2100 1600) $PN 1
J 0
(2105 1562);
DISPLAY 0.787234 (2105 1562);
PAINT MONO (2105 1562);
FORCEPROP 1 LASTPIN (2100 1400) $PN 2
J 0
(2105 1410);
DISPLAY 0.787234 (2105 1410);
PAINT MONO (2105 1410);
FORCEPROP 1 LAST PATH I62
J 0
(2150 1675);
DISPLAY 0.978723 (2150 1675);
PAINT WHITE (2150 1675);
DISPLAY INVISIBLE (2150 1675);
FORCEPROP 2 LAST CDS_LIB pure_quanta
J 0
(2100 1500);
DISPLAY INVISIBLE (2100 1500);
FORCEPROP 0 LAST CDS_LOCATION R3495
J 0
(2150 1675);
DISPLAY 1.021277 (2150 1675);
DISPLAY INVISIBLE (2150 1675);
FORCEPROP 0 LAST $SEC 1
J 0
(2150 1675);
DISPLAY 0.680851 (2150 1675);
PAINT MONO (2150 1675);
DISPLAY INVISIBLE (2150 1675);
FORCEPROP 0 LAST CDS_SEC 1
J 0
(2150 1675);
DISPLAY 1.021277 (2150 1675);
DISPLAY INVISIBLE (2150 1675);
FORCEADD UNIVERSAL_GND..1
(2100 1300);
FORCEPROP 3 LASTPIN (2100 1350) SIG_NAME GND\g
J 0
(2110 1360);
DISPLAY 0.659574 (2110 1360);
PAINT MONO (2110 1360);
DISPLAY INVISIBLE (2110 1360);
FORCEPROP 1 LAST PATH I63
J 0
(2175 1300);
DISPLAY 0.872340 (2175 1300);
PAINT AQUA (2175 1300);
DISPLAY INVISIBLE (2175 1300);
FORCEPROP 2 LAST CDS_LIB logical_power
J 0
(2100 1300);
DISPLAY INVISIBLE (2100 1300);
FORCEPROP 1 LAST HDL_POWER GND
J 1
(2125 1225);
DISPLAY 0.872340 (2125 1225);
PAINT GREEN (2125 1225);
DISPLAY INVISIBLE (2125 1225);
FORCEADD UNIVERSAL_POWER..1
(1350 1375);
FORCEPROP 3 LASTPIN (1350 1325) SIG_NAME P3V3_AUX\g
J 0
(1360 1335);
DISPLAY 0.659574 (1360 1335);
PAINT MONO (1360 1335);
DISPLAY INVISIBLE (1360 1335);
FORCEPROP 1 LAST HDL_POWER P3V3_AUX
J 1
(1350 1425);
DISPLAY 0.872340 (1350 1425);
PAINT GREEN (1350 1425);
FORCEPROP 1 LAST PATH I66
J 0
(1400 1400);
DISPLAY 0.872340 (1400 1400);
PAINT AQUA (1400 1400);
DISPLAY INVISIBLE (1400 1400);
FORCEPROP 2 LAST CDS_LIB logical_power
J 0
(1350 1375);
PAINT MONO (1350 1375);
DISPLAY INVISIBLE (1350 1375);
FORCEADD Q_CAP..1
(1350 1050);
FORCEPROP 1 LAST PART_NUMBER CH4104K1B00
J 0
(1400 900);
DISPLAY 0.510638 (1400 900);
DISPLAY INVISIBLE (1400 900);
FORCEPROP 1 LAST PACK_TYPE 0402
J 0
(1400 850);
DISPLAY 0.510638 (1400 850);
FORCEPROP 1 LAST MATERIAL X7R
J 0
(1400 950);
DISPLAY 0.510638 (1400 950);
FORCEPROP 1 LAST VOLTAGE 25V
J 0
(1400 1050);
DISPLAY 0.510638 (1400 1050);
FORCEPROP 1 LAST VALUE 0.1UF
J 0
(1400 1100);
DISPLAY 0.510638 (1400 1100);
FORCEPROP 1 LAST TOLERANCE 10%
J 0
(1400 1000);
DISPLAY 0.510638 (1400 1000);
FORCEPROP 1 LAST $LOCATION C1979
J 0
(1400 1150);
DISPLAY 0.787234 (1400 1150);
FORCEPROP 1 LASTPIN (1350 1150) $PN 1
J 0
(1360 1130);
DISPLAY 0.787234 (1360 1130);
FORCEPROP 1 LASTPIN (1350 950) $PN 2
J 0
(1360 930);
DISPLAY 0.787234 (1360 930);
FORCEPROP 1 LAST PATH I67
J 0
(1400 1200);
DISPLAY 0.978723 (1400 1200);
PAINT WHITE (1400 1200);
DISPLAY INVISIBLE (1400 1200);
FORCEPROP 2 LAST CDS_LIB pure_quanta
J 2
(1350 1050);
PAINT MONO (1350 1050);
DISPLAY INVISIBLE (1350 1050);
FORCEPROP 2 LAST CDS_LOCATION C1979
J 0
(1400 1250);
DISPLAY 1.021277 (1400 1250);
DISPLAY INVISIBLE (1400 1250);
FORCEPROP 2 LAST $SEC 1
J 0
(1400 1250);
DISPLAY 0.680851 (1400 1250);
PAINT MONO (1400 1250);
DISPLAY INVISIBLE (1400 1250);
FORCEPROP 2 LAST CDS_SEC 1
J 0
(1400 1250);
DISPLAY 1.021277 (1400 1250);
DISPLAY INVISIBLE (1400 1250);
FORCEADD UNIVERSAL_GND..1
(1350 825);
FORCEPROP 3 LASTPIN (1350 875) SIG_NAME GND\g
J 0
(1360 885);
DISPLAY 0.659574 (1360 885);
PAINT MONO (1360 885);
DISPLAY INVISIBLE (1360 885);
FORCEPROP 1 LAST PATH I68
J 0
(1425 825);
DISPLAY 0.872340 (1425 825);
PAINT AQUA (1425 825);
DISPLAY INVISIBLE (1425 825);
FORCEPROP 2 LAST CDS_LIB logical_power
J 0
(1350 825);
PAINT MONO (1350 825);
DISPLAY INVISIBLE (1350 825);
FORCEPROP 1 LAST HDL_POWER GND
J 1
(1375 750);
DISPLAY 0.872340 (1375 750);
PAINT GREEN (1375 750);
DISPLAY INVISIBLE (1375 750);
FORCEADD UNIVERSAL_GND..1
(200 1100);
FORCEPROP 3 LASTPIN (200 1150) SIG_NAME GND\g
J 0
(210 1160);
DISPLAY 0.659574 (210 1160);
PAINT MONO (210 1160);
DISPLAY INVISIBLE (210 1160);
FORCEPROP 1 LAST PATH I69
J 0
(275 1100);
DISPLAY 0.872340 (275 1100);
PAINT AQUA (275 1100);
DISPLAY INVISIBLE (275 1100);
FORCEPROP 2 LAST CDS_LIB logical_power
J 0
(200 1100);
DISPLAY INVISIBLE (200 1100);
FORCEPROP 1 LAST HDL_POWER GND
J 1
(225 1025);
DISPLAY 0.872340 (225 1025);
PAINT GREEN (225 1025);
DISPLAY INVISIBLE (225 1025);
FORCEADD Q_RES..2
(-600 1600);
FORCEPROP 1 LAST PART_NUMBER CS41002FB09
J 0
(-560 1475);
DISPLAY 0.510638 (-560 1475);
DISPLAY INVISIBLE (-560 1475);
FORCEPROP 1 LAST VALUE 100K
J 0
(-555 1675);
DISPLAY 0.510638 (-555 1675);
FORCEPROP 1 LAST TOLERANCE 1%
J 0
(-555 1625);
DISPLAY 0.510638 (-555 1625);
FORCEPROP 1 LAST WATTAGE 1/16W
J 0
(-560 1575);
DISPLAY 0.510638 (-560 1575);
FORCEPROP 1 LAST PACK_TYPE 0402LF
J 0
(-560 1425);
DISPLAY 0.510638 (-560 1425);
FORCEPROP 1 LAST MATERIAL EMPTY
J 0
(-560 1525);
DISPLAY 0.510638 (-560 1525);
PAINT RED (-560 1525);
FORCEPROP 1 LAST $LOCATION R3491
J 0
(-555 1725);
DISPLAY 0.978723 (-555 1725);
FORCEPROP 1 LASTPIN (-600 1700) $PN 1
J 0
(-595 1662);
DISPLAY 0.787234 (-595 1662);
PAINT MONO (-595 1662);
FORCEPROP 1 LASTPIN (-600 1500) $PN 2
J 0
(-595 1510);
DISPLAY 0.787234 (-595 1510);
PAINT MONO (-595 1510);
FORCEPROP 1 LAST PATH I70
J 0
(-550 1775);
DISPLAY 0.978723 (-550 1775);
PAINT WHITE (-550 1775);
DISPLAY INVISIBLE (-550 1775);
FORCEPROP 2 LAST CDS_LIB pure_quanta
J 0
(-600 1600);
DISPLAY INVISIBLE (-600 1600);
FORCEPROP 0 LAST CDS_LOCATION R3491
J 0
(-550 1775);
DISPLAY 1.021277 (-550 1775);
DISPLAY INVISIBLE (-550 1775);
FORCEPROP 0 LAST $SEC 1
J 0
(-550 1775);
DISPLAY 0.680851 (-550 1775);
PAINT MONO (-550 1775);
DISPLAY INVISIBLE (-550 1775);
FORCEPROP 0 LAST CDS_SEC 1
J 0
(-550 1775);
DISPLAY 1.021277 (-550 1775);
DISPLAY INVISIBLE (-550 1775);
FORCEADD UNIVERSAL_GND..1
(-600 1400);
FORCEPROP 3 LASTPIN (-600 1450) SIG_NAME GND\g
J 0
(-590 1460);
DISPLAY 0.659574 (-590 1460);
PAINT MONO (-590 1460);
DISPLAY INVISIBLE (-590 1460);
FORCEPROP 1 LAST PATH I74
J 0
(-525 1400);
DISPLAY 0.872340 (-525 1400);
PAINT AQUA (-525 1400);
DISPLAY INVISIBLE (-525 1400);
FORCEPROP 1 LAST HDL_POWER GND
J 1
(-575 1325);
DISPLAY 0.872340 (-575 1325);
PAINT GREEN (-575 1325);
DISPLAY INVISIBLE (-575 1325);
FORCEPROP 2 LAST CDS_LIB logical_power
J 0
(-600 1400);
DISPLAY INVISIBLE (-600 1400);
FORCEADD DNS..2
(-600 1575);
PAINT RED (-600 1575);
FORCEPROP 1 LAST COMMENT_BODY TRUE
J 0
(-600 1575);
DISPLAY INVISIBLE (-600 1575);
FORCEPROP 2 LAST CDS_LIB mstr_misc
J 0
(-600 1575);
DISPLAY INVISIBLE (-600 1575);
FORCEADD DNS..2
(-625 2925);
PAINT RED (-625 2925);
FORCEPROP 2 LAST CDS_LIB mstr_misc
J 0
(-625 2925);
DISPLAY INVISIBLE (-625 2925);
FORCEPROP 1 LAST COMMENT_BODY TRUE
J 0
(-625 2925);
DISPLAY INVISIBLE (-625 2925);
FORCEADD DNS..2
(-625 4075);
PAINT RED (-625 4075);
FORCEPROP 1 LAST COMMENT_BODY TRUE
J 0
(-625 4075);
DISPLAY INVISIBLE (-625 4075);
FORCEPROP 2 LAST CDS_LIB mstr_misc
J 0
(-625 4075);
DISPLAY INVISIBLE (-625 4075);
FORCEADD DNS..2
(2100 1475);
PAINT RED (2100 1475);
FORCEPROP 1 LAST COMMENT_BODY TRUE
J 0
(2100 1475);
DISPLAY INVISIBLE (2100 1475);
FORCEPROP 2 LAST CDS_LIB mstr_misc
J 0
(2100 1475);
DISPLAY INVISIBLE (2100 1475);
FORCEADD DNS..2
(1925 2775);
PAINT RED (1925 2775);
FORCEPROP 1 LAST COMMENT_BODY TRUE
J 0
(1925 2775);
DISPLAY INVISIBLE (1925 2775);
FORCEPROP 2 LAST CDS_LIB mstr_misc
J 0
(1925 2775);
DISPLAY INVISIBLE (1925 2775);
FORCEADD DNS..2
(1875 3975);
PAINT RED (1875 3975);
FORCEPROP 1 LAST COMMENT_BODY TRUE
J 0
(1875 3975);
DISPLAY INVISIBLE (1875 3975);
FORCEPROP 2 LAST CDS_LIB mstr_misc
J 0
(1875 3975);
DISPLAY INVISIBLE (1875 3975);
FORCEADD QUANTA_TITLE_BLOCK_C..1
(5475 -1300);
FORCEPROP 0 LAST CDS_CON_LAST_MODIFIED Fri Aug 25 14:02:12 2023
J 0
(3590 -1285);
DISPLAY INVISIBLE (3590 -1285);
FORCEPROP 1 LAST CUSTOM_TXT_CDS <CON_LAST_MODIFIED>
J 0
(3590 -1285);
DISPLAY 0.978723 (3590 -1285);
FORCEPROP 2 LAST CUSTOM_TXT_CDS <XR_PAGE_TITLE>
J 0
(-2415 3950);
DISPLAY 0.638298 (-2415 3950);
PAINT PINK (-2415 3950);
DISPLAY INVISIBLE (-2415 3950);
FORCEPROP 1 LAST CUSTOM_TXT_CDS <NAME_2>
J 0
(2300 -1250);
FORCEPROP 1 LAST CUSTOM_TXT_CDS <NAME_1>
J 0
(2300 -1125);
FORCEPROP 1 LAST CUSTOM_TXT_CDS <Q_NUMBER>
J 0
(4072 -1197);
DISPLAY 1.212766 (4072 -1197);
FORCEPROP 1 LAST CUSTOM_TXT_CDS <Q_PROJ>
J 0
(3093 -1198);
DISPLAY 1.212766 (3093 -1198);
FORCEPROP 1 LAST CUSTOM_TXT_CDS <Q_REV>
J 0
(5291 -1197);
DISPLAY 1.212766 (5291 -1197);
FORCEPROP 1 LAST CUSTOM_TXT_CDS <CON_PAGE_NUM> OF <CON_TOTAL_PAGES>
J 0
(5029 -1282);
DISPLAY 0.978723 (5029 -1282);
FORCEPROP 1 LAST Q_TITLE EXAMAX_ISO (6/7)
J 0
(-3825 -1250);
DISPLAY 2.446809 (-3825 -1250);
PAINT GREEN (-3825 -1250);
FORCEPROP 1 LAST Q_DEPT 
J 1
(1712 -1251);
DISPLAY 1.957447 (1712 -1251);
PAINT GREEN (1712 -1251);
FORCEPROP 2 LAST CDS_XR_PAGE_TITLE CR-150 : @S9S_MB_2U_LIB.S9S_MB_2U(SCH_1):PAGE150
J 0
(-2415 3950);
DISPLAY 0.638298 (-2415 3950);
PAINT PINK (-2415 3950);
DISPLAY INVISIBLE (-2415 3950);
FORCEPROP 2 LAST PAGE_BORDER TRUE
J 0
(-2415 3950);
DISPLAY 0.638298 (-2415 3950);
PAINT PINK (-2415 3950);
DISPLAY INVISIBLE (-2415 3950);
FORCEPROP 1 LAST COMMENT_BODY TRUE
J 0
(5487 -1313);
DISPLAY 0.978723 (5487 -1313);
PAINT GREEN (5487 -1313);
DISPLAY INVISIBLE (5487 -1313);
FORCEPROP 1 LAST CDS_LMAN_SYM_OUTLINE -9475,6775,100,-125
J 0
(5475 -1300);
DISPLAY 0.468085 (5475 -1300);
PAINT GREEN (5475 -1300);
DISPLAY INVISIBLE (5475 -1300);
FORCEPROP 2 LAST CDS_LIB pure_quanta
J 0
(5475 -1300);
DISPLAY INVISIBLE (5475 -1300);
WIRE 16 -1 (1350 1325)(1350 1250);
WIRE 16 -1 (-650 2275)(-650 2175);
WIRE 16 -1 (2075 2300)(2075 2200);
WIRE 16 -1 (-650 3625)(-650 3525);
WIRE 16 -1 (1350 3825)(1350 3750);
WIRE 16 -1 (1900 3600)(1900 3500);
WIRE 16 -1 (-650 4775)(-650 4675);
WIRE 16 -1 (1850 4800)(1850 4700);
WIRE 16 -1 (-600 1450)(-600 1500);
WIRE 16 -1 (-625 2800)(-625 2850);
WIRE 16 -1 (-625 3950)(-625 4000);
WIRE 16 -1 (200 1200)(200 1150);
WIRE 16 -1 (200 1250)(200 1200);
WIRE 16 -1 (450 1200)(200 1200);
WIRE 16 -1 (200 3750)(200 3650);
WIRE 16 -1 (450 3750)(200 3750);
WIRE 16 -1 (1350 950)(1350 875);
WIRE 16 -1 (2100 1400)(2100 1350);
WIRE 16 -1 (1350 3450)(1350 3375);
WIRE 16 -1 (1925 2700)(1925 2650);
WIRE 16 -1 (1875 3900)(1875 3850);
WIRE 16 2175 (75 1025)(375 1025);
WIRE 16 2175 (375 1350)(375 1025);
WIRE 16 2175 (75 1350)(75 1025);
WIRE 16 2175 (75 1350)(375 1350);
WIRE 16 -1 (450 1250)(200 1250);
WIRE 16 -1 (-650 1800)(-850 1800);
WIRE 16 -1 (-650 1975)(-650 1800);
WIRE 16 -1 (-600 1700)(-600 1800);
WIRE 16 -1 (-650 1800)(-600 1800);
WIRE 16 -1 (450 1800)(-600 1800);
FORCEPROP 2 LAST SIG_NAME GPU_FPGA_EROT_RECOV_N
J 0
(-585 1810);
DISPLAY 0.808511 (-585 1810);
WIRE 16 -1 (450 1800)(450 1300);
WIRE 16 -1 (2100 1600)(2100 1800);
WIRE 16 -1 (2100 1800)(2225 1800);
WIRE 16 -1 (2075 1800)(2100 1800);
WIRE 16 -1 (2075 2000)(2075 1800);
WIRE 16 -1 (1100 1800)(1100 1300);
WIRE 16 -1 (1100 1800)(2075 1800);
FORCEPROP 2 LAST SIG_NAME GPU_FPGA_EROT_RECOV_BUF_R_N
J 0
(1140 1810);
DISPLAY 0.638298 (1140 1810);
WIRE 16 -1 (1100 3700)(1100 3100);
WIRE 16 -1 (1900 3100)(1100 3100);
FORCEPROP 2 LAST SIG_NAME GPU_FPGA_EROT_RST_BUF_R_N
J 0
(1115 3110);
DISPLAY 0.638298 (1115 3110);
WIRE 16 -1 (1900 3300)(1900 3100);
WIRE 16 -1 (1900 3100)(1925 3100);
WIRE 16 -1 (1925 3100)(2050 3100);
WIRE 16 -1 (1925 2900)(1925 3100);
WIRE 16 -1 (-650 3150)(-850 3150);
WIRE 16 -1 (-650 3325)(-650 3150);
WIRE 16 -1 (-625 3050)(-625 3150);
WIRE 16 -1 (-625 3150)(-650 3150);
WIRE 16 -1 (450 3150)(-625 3150);
FORCEPROP 2 LAST SIG_NAME GPU_FPGA_EROT_RST_N
J 0
(-585 3160);
DISPLAY 0.808511 (-585 3160);
WIRE 16 -1 (450 3150)(450 3700);
WIRE 16 -1 (450 4300)(450 3800);
WIRE 16 -1 (-625 4200)(-625 4300);
WIRE 16 -1 (450 4300)(-625 4300);
FORCEPROP 2 LAST SIG_NAME GPU_NVS_PWR_BRAKE_N
J 0
(-585 4310);
DISPLAY 0.808511 (-585 4310);
WIRE 16 -1 (-650 4300)(-850 4300);
WIRE 16 -1 (-625 4300)(-650 4300);
WIRE 16 -1 (-650 4475)(-650 4300);
WIRE 16 -1 (1800 1200)(1100 1200);
FORCEPROP 2 LAST SIG_NAME NC_U257_2Y
J 0
(1365 1210);
DISPLAY 0.808511 (1365 1210);
WIRE 16 -1 (1875 4100)(1875 4300);
WIRE 16 -1 (1875 4300)(2000 4300);
WIRE 16 -1 (1850 4300)(1875 4300);
WIRE 16 -1 (1850 4500)(1850 4300);
WIRE 16 -1 (1100 4300)(1100 3800);
WIRE 16 -1 (1100 4300)(1850 4300);
FORCEPROP 2 LAST SIG_NAME GPU_NVS_PWR_BRAKE_N_R
J 0
(1115 4310);
DISPLAY 0.638298 (1115 4310);
WIRE 16 -1 (1350 1250)(1350 1150);
WIRE 16 -1 (1100 1250)(1350 1250);
WIRE 16 -1 (3550 1800)(2425 1800);
FORCEPROP 2 LAST SIG_NAME GPU_FPGA_EROT_RECOV_BUF_N
J 0
(2615 1810);
DISPLAY 0.808511 (2615 1810);
WIRE 16 -1 (3375 3100)(2250 3100);
FORCEPROP 2 LAST SIG_NAME GPU_FPGA_EROT_RST_BUF_N
J 0
(2440 3110);
DISPLAY 0.808511 (2440 3110);
WIRE 16 -1 (3325 4300)(2200 4300);
FORCEPROP 2 LAST SIG_NAME GPU_NVS_PWR_BRAKE_N_BUF
J 0
(2390 4310);
DISPLAY 0.808511 (2390 4310);
WIRE 16 -1 (1100 3750)(1350 3750);
WIRE 16 -1 (1350 3750)(1350 3650);
DOT 1 (-600 1800);
DOT 1 (-625 3150);
DOT 1 (-625 4300);
DOT 1 (-650 1800);
DOT 1 (-650 3150);
DOT 1 (1350 1250);
DOT 1 (2100 1800);
DOT 1 (2075 1800);
DOT 1 (1350 3750);
DOT 1 (1900 3100);
DOT 1 (1925 3100);
DOT 1 (-650 4300);
DOT 1 (1850 4300);
DOT 1 (1875 4300);
DOT 1 (200 1200);
FORCENOTE
20210603 MODIFY FOR GT
(-3700 5075) 0;
DISPLAY LEFT (-3700 5075);
DISPLAY 2.510638 (-3700 5075);
PAINT PINK (-3700 5075);
FORCENOTE
OPEN-DRAIN OUTPUT
(325 3000) 0;
DISPLAY LEFT (325 3000);
DISPLAY 1.021277 (325 3000);
PAINT WHITE (325 3000);
FORCENOTE
OPEN-DRAIN OUTPUT
(400 1000) 0;
DISPLAY LEFT (400 1000);
DISPLAY 1.021277 (400 1000);
PAINT WHITE (400 1000);
FORCENOTE
20220105 CHANGE PIN3 CONNECT TO GND
(-925 875) 0;
DISPLAY LEFT (-925 875);
DISPLAY 0.808511 (-925 875);
PAINT WHITE (-925 875);
QUIT
